(kicad_pcb
	(version 20260206)
	(generator "pcbnew")
	(generator_version "10.0")
	(general
		(thickness 1.21888)
		(legacy_teardrops no)
	)
	(paper "A4")
	(title_block
		(title "timecard-v9 — TimeCard-DC-V9_EXP.PcbDoc")
		(comment 1 "Time Appliance Project (Time Card) / footprints 155-155 of 402")
	)
	(layers
		(0 "F.Cu" signal "TOP")
		(4 "In1.Cu" signal "SGND")
		(6 "In2.Cu" signal "IN1")
		(8 "In3.Cu" signal "IN2")
		(10 "In4.Cu" signal "SGND1")
		(2 "B.Cu" signal "BOTTOM")
		(9 "F.Adhes" user "F.Adhesive")
		(11 "B.Adhes" user "B.Adhesive")
		(13 "F.Paste" user "Top Paste")
		(15 "B.Paste" user "Bottom Paste")
		(5 "F.SilkS" user "Top Overlay")
		(7 "B.SilkS" user "Bottom Overlay")
		(1 "F.Mask" user "Top Solder")
		(3 "B.Mask" user "Bottom Solder")
		(17 "Dwgs.User" user "User.Drawings")
		(19 "Cmts.User" user "User.Comments")
		(21 "Eco1.User" user "User.Eco1")
		(23 "Eco2.User" user "User.Eco2")
		(25 "Edge.Cuts" user)
		(27 "Margin" user)
		(31 "F.CrtYd" user "Top Courtyard")
		(29 "B.CrtYd" user "Bottom Courtyard")
		(35 "F.Fab" user "Top Component Center")
		(33 "B.Fab" user "Bottom Component Center")
	)
	(footprint "Vault:FP-2199119-3-MFG"
		(locked yes)
		(layer "F.Cu")
		(at 208.2216 125.4162 180)
		(property "Reference" "J45"
			(at -11.873069 1.0968 270)
			(unlocked yes)
			(layer "F.SilkS")
			(effects
				(font
					(size 0.762 0.762)
					(thickness 0.2032)
				)
			)
		)
		(property "Value" "2199119-3"
			(at -12.739871 1.153695 90)
			(unlocked yes)
			(layer "F.SilkS")
			(hide yes)
			(effects
				(font
					(size 0.762 0.762)
					(thickness 0.2032)
				)
			)
		)
		(sheetname "10-M2_GPS")
		(sheetfile "10-M2_GPS.kicad_sch")
		(duplicate_pad_numbers_are_jumpers no)
		(fp_line
			(start 11 3.975)
			(end 9.525 3.975)
			(stroke
				(width 0.2)
				(type solid)
			)
			(layer "F.SilkS")
		)
		(fp_line
			(start 11 2.55)
			(end 11 3.975)
			(stroke
				(width 0.2)
				(type solid)
			)
			(layer "F.SilkS")
		)
		(fp_line
			(start 11 -1.375)
			(end 11 0.2)
			(stroke
				(width 0.2)
				(type solid)
			)
			(layer "F.SilkS")
		)
		(fp_line
			(start -4.775 -3.975)
			(end -6.225 -3.975)
			(stroke
				(width 0.2)
				(type solid)
			)
			(layer "F.SilkS")
		)
		(fp_line
			(start -5.025 3.975)
			(end -6.475 3.975)
			(stroke
				(width 0.2)
				(type solid)
			)
			(layer "F.SilkS")
		)
		(fp_line
			(start -9.525 3.975)
			(end -11 3.975)
			(stroke
				(width 0.2)
				(type solid)
			)
			(layer "F.SilkS")
		)
		(fp_line
			(start -11 -1.375)
			(end -11 3.975)
			(stroke
				(width 0.2)
				(type solid)
			)
			(layer "F.SilkS")
		)
		(fp_circle
			(center -9.275 -5.275)
			(end -9.275 -5.15)
			(stroke
				(width 0.25)
				(type solid)
			)
			(fill no)
			(layer "F.SilkS")
		)
		(fp_line
			(start 11.1 4.525)
			(end -11.1 4.525)
			(stroke
				(width 0.2)
				(type solid)
			)
			(layer "F.CrtYd")
		)
		(fp_line
			(start 11.1 -4.775)
			(end 11.1 4.525)
			(stroke
				(width 0.2)
				(type solid)
			)
			(layer "F.CrtYd")
		)
		(fp_line
			(start 11.1 -4.775)
			(end -11.1 -4.775)
			(stroke
				(width 0.2)
				(type solid)
			)
			(layer "F.CrtYd")
		)
		(fp_line
			(start -11.1 -4.775)
			(end -11.1 4.525)
			(stroke
				(width 0.2)
				(type solid)
			)
			(layer "F.CrtYd")
		)
		(fp_line
			(start 11.1 4.525)
			(end -11.1 4.525)
			(stroke
				(width 0.2)
				(type solid)
			)
			(layer "F.Fab")
		)
		(fp_line
			(start 11.1 -4.775)
			(end 11.1 4.525)
			(stroke
				(width 0.2)
				(type solid)
			)
			(layer "F.Fab")
		)
		(fp_line
			(start 11.1 -4.775)
			(end -11.1 -4.775)
			(stroke
				(width 0.2)
				(type solid)
			)
			(layer "F.Fab")
		)
		(fp_line
			(start 0.5 0)
			(end -0.5 0)
			(stroke
				(width 0.1)
				(type solid)
			)
			(layer "F.Fab")
		)
		(fp_line
			(start 0 -0.5)
			(end 0 0.5)
			(stroke
				(width 0.1)
				(type solid)
			)
			(layer "F.Fab")
		)
		(fp_line
			(start -11.1 -4.775)
			(end -11.1 4.525)
			(stroke
				(width 0.2)
				(type solid)
			)
			(layer "F.Fab")
		)
		(fp_text user "${REFERENCE}"
			(at -0.00185 0.15925 180)
			(unlocked yes)
			(layer "F.Fab")
			(effects
				(font
					(face "Arial")
					(size 0.63 0.63)
					(thickness 0.1)
				)
				(justify left bottom)
			)
		)
		(pad "" np_thru_hole circle
			(at -10 1.375 180)
			(size 1.1 1.1)
			(drill 1.1)
			(layers "*.Cu" "*.Mask")
			(solder_mask_margin 0)
			(solder_paste_margin -1000)
			(thermal_bridge_angle 90)
		)
		(pad "" np_thru_hole circle
			(at 10 1.375 180)
			(size 1.6 1.6)
			(drill 1.6)
			(layers "*.Cu" "*.Mask")
			(solder_mask_margin 0)
			(solder_paste_margin -1000)
			(thermal_bridge_angle 90)
		)
		(pad "1" smd rect
			(at -9.25 -3.9 180)
			(size 0.3 1.55)
			(layers "F.Cu" "F.Mask" "F.Paste")
			(solder_mask_margin 0)
			(solder_paste_margin 0)
		)
		(pad "2" smd rect
			(at -9 3.65 180)
			(size 0.3 1.55)
			(layers "F.Cu" "F.Mask" "F.Paste")
			(net "GNSS2_P3V3")
			(solder_mask_margin 0)
			(solder_paste_margin 0)
		)
		(pad "3" smd rect
			(at -8.75 -3.9 180)
			(size 0.3 1.55)
			(layers "F.Cu" "F.Mask" "F.Paste")
			(net "GND")
			(solder_mask_margin 0)
			(solder_paste_margin 0)
		)
		(pad "4" smd rect
			(at -8.5 3.65 180)
			(size 0.3 1.55)
			(layers "F.Cu" "F.Mask" "F.Paste")
			(net "GNSS2_P3V3")
			(solder_mask_margin 0)
			(solder_paste_margin 0)
		)
		(pad "5" smd rect
			(at -8.25 -3.9 180)
			(size 0.3 1.55)
			(layers "F.Cu" "F.Mask" "F.Paste")
			(net "GND")
			(solder_mask_margin 0)
			(solder_paste_margin 0)
		)
		(pad "6" smd rect
			(at -8 3.65 180)
			(size 0.3 1.55)
			(layers "F.Cu" "F.Mask" "F.Paste")
			(solder_mask_margin 0)
			(solder_paste_margin 0)
		)
		(pad "7" smd rect
			(at -7.75 -3.9 180)
			(size 0.3 1.55)
			(layers "F.Cu" "F.Mask" "F.Paste")
			(solder_mask_margin 0)
			(solder_paste_margin 0)
		)
		(pad "8" smd rect
			(at -7.5 3.65 180)
			(size 0.3 1.55)
			(layers "F.Cu" "F.Mask" "F.Paste")
			(solder_mask_margin 0)
			(solder_paste_margin 0)
		)
		(pad "9" smd rect
			(at -7.25 -3.9 180)
			(size 0.3 1.55)
			(layers "F.Cu" "F.Mask" "F.Paste")
			(solder_mask_margin 0)
			(solder_paste_margin 0)
		)
		(pad "10" smd rect
			(at -7 3.65 180)
			(size 0.3 1.55)
			(layers "F.Cu" "F.Mask" "F.Paste")
			(solder_mask_margin 0)
			(solder_paste_margin 0)
		)
		(pad "11" smd rect
			(at -6.75 -3.9 180)
			(size 0.3 1.55)
			(layers "F.Cu" "F.Mask" "F.Paste")
			(net "GND")
			(solder_mask_margin 0)
			(solder_paste_margin 0)
		)
		(pad "20" smd rect
			(at -4.5 3.65 180)
			(size 0.3 1.55)
			(layers "F.Cu" "F.Mask" "F.Paste")
			(net "M2_GPS2_PIN11")
			(solder_mask_margin 0)
			(solder_paste_margin 0)
		)
		(pad "21" smd rect
			(at -4.25 -3.9 180)
			(size 0.3 1.55)
			(layers "F.Cu" "F.Mask" "F.Paste")
			(solder_mask_margin 0)
			(solder_paste_margin 0)
		)
		(pad "22" smd rect
			(at -4 3.65 180)
			(size 0.3 1.55)
			(layers "F.Cu" "F.Mask" "F.Paste")
			(net "M2_GPS2_PIN12")
			(solder_mask_margin 0)
			(solder_paste_margin 0)
		)
		(pad "23" smd rect
			(at -3.75 -3.9 180)
			(size 0.3 1.55)
			(layers "F.Cu" "F.Mask" "F.Paste")
			(solder_mask_margin 0)
			(solder_paste_margin 0)
		)
		(pad "24" smd rect
			(at -3.5 3.65 180)
			(size 0.3 1.55)
			(layers "F.Cu" "F.Mask" "F.Paste")
			(solder_mask_margin 0)
			(solder_paste_margin 0)
		)
		(pad "25" smd rect
			(at -3.25 -3.9 180)
			(size 0.3 1.55)
			(layers "F.Cu" "F.Mask" "F.Paste")
			(solder_mask_margin 0)
			(solder_paste_margin 0)
		)
		(pad "26" smd rect
			(at -3 3.65 180)
			(size 0.3 1.55)
			(layers "F.Cu" "F.Mask" "F.Paste")
			(solder_mask_margin 0)
			(solder_paste_margin 0)
		)
		(pad "27" smd rect
			(at -2.75 -3.9 180)
			(size 0.3 1.55)
			(layers "F.Cu" "F.Mask" "F.Paste")
			(net "GND")
			(solder_mask_margin 0)
			(solder_paste_margin 0)
		)
		(pad "28" smd rect
			(at -2.5 3.65 180)
			(size 0.3 1.55)
			(layers "F.Cu" "F.Mask" "F.Paste")
			(solder_mask_margin 0)
			(solder_paste_margin 0)
		)
		(pad "29" smd rect
			(at -2.25 -3.9 180)
			(size 0.3 1.55)
			(layers "F.Cu" "F.Mask" "F.Paste")
			(solder_mask_margin 0)
			(solder_paste_margin 0)
		)
		(pad "30" smd rect
			(at -2 3.65 180)
			(size 0.3 1.55)
			(layers "F.Cu" "F.Mask" "F.Paste")
			(solder_mask_margin 0)
			(solder_paste_margin 0)
		)
		(pad "31" smd rect
			(at -1.75 -3.9 180)
			(size 0.3 1.55)
			(layers "F.Cu" "F.Mask" "F.Paste")
			(solder_mask_margin 0)
			(solder_paste_margin 0)
		)
		(pad "32" smd rect
			(at -1.5 3.65 180)
			(size 0.3 1.55)
			(layers "F.Cu" "F.Mask" "F.Paste")
			(solder_mask_margin 0)
			(solder_paste_margin 0)
		)
		(pad "33" smd rect
			(at -1.25 -3.9 180)
			(size 0.3 1.55)
			(layers "F.Cu" "F.Mask" "F.Paste")
			(net "GND")
			(solder_mask_margin 0)
			(solder_paste_margin 0)
		)
		(pad "34" smd rect
			(at -1 3.65 180)
			(size 0.3 1.55)
			(layers "F.Cu" "F.Mask" "F.Paste")
			(solder_mask_margin 0)
			(solder_paste_margin 0)
		)
		(pad "35" smd rect
			(at -0.75 -3.9 180)
			(size 0.3 1.55)
			(layers "F.Cu" "F.Mask" "F.Paste")
			(net "NetJ45_35")
			(solder_mask_margin 0)
			(solder_paste_margin 0)
		)
		(pad "36" smd rect
			(at -0.5 3.65 180)
			(size 0.3 1.55)
			(layers "F.Cu" "F.Mask" "F.Paste")
			(solder_mask_margin 0)
			(solder_paste_margin 0)
		)
		(pad "37" smd rect
			(at -0.25 -3.9 180)
			(size 0.3 1.55)
			(layers "F.Cu" "F.Mask" "F.Paste")
			(solder_mask_margin 0)
			(solder_paste_margin 0)
		)
		(pad "38" smd rect
			(at 0 3.65 180)
			(size 0.3 1.55)
			(layers "F.Cu" "F.Mask" "F.Paste")
			(solder_mask_margin 0)
			(solder_paste_margin 0)
		)
		(pad "39" smd rect
			(at 0.25 -3.9 180)
			(size 0.3 1.55)
			(layers "F.Cu" "F.Mask" "F.Paste")
			(net "GND")
			(solder_mask_margin 0)
			(solder_paste_margin 0)
		)
		(pad "40" smd rect
			(at 0.5 3.65 180)
			(size 0.3 1.55)
			(layers "F.Cu" "F.Mask" "F.Paste")
			(net "GPS2_PIN13")
			(solder_mask_margin 0)
			(solder_paste_margin 0)
		)
		(pad "41" smd rect
			(at 0.75 -3.9 180)
			(size 0.3 1.55)
			(layers "F.Cu" "F.Mask" "F.Paste")
			(solder_mask_margin 0)
			(solder_paste_margin 0)
		)
		(pad "42" smd rect
			(at 1 3.65 180)
			(size 0.3 1.55)
			(layers "F.Cu" "F.Mask" "F.Paste")
			(net "GPS2_PIN14")
			(solder_mask_margin 0)
			(solder_paste_margin 0)
		)
		(pad "43" smd rect
			(at 1.25 -3.9 180)
			(size 0.3 1.55)
			(layers "F.Cu" "F.Mask" "F.Paste")
			(solder_mask_margin 0)
			(solder_paste_margin 0)
		)
		(pad "44" smd rect
			(at 1.5 3.65 180)
			(size 0.3 1.55)
			(layers "F.Cu" "F.Mask" "F.Paste")
			(net "GPS2_PIN15")
			(solder_mask_margin 0)
			(solder_paste_margin 0)
		)
		(pad "45" smd rect
			(at 1.75 -3.9 180)
			(size 0.3 1.55)
			(layers "F.Cu" "F.Mask" "F.Paste")
			(net "GND")
			(solder_mask_margin 0)
			(solder_paste_margin 0)
		)
		(pad "46" smd rect
			(at 2 3.65 180)
			(size 0.3 1.55)
			(layers "F.Cu" "F.Mask" "F.Paste")
			(net "NetJ45_46")
			(solder_mask_margin 0)
			(solder_paste_margin 0)
		)
		(pad "47" smd rect
			(at 2.25 -3.9 180)
			(size 0.3 1.55)
			(layers "F.Cu" "F.Mask" "F.Paste")
			(solder_mask_margin 0)
			(solder_paste_margin 0)
		)
		(pad "48" smd rect
			(at 2.5 3.65 180)
			(size 0.3 1.55)
			(layers "F.Cu" "F.Mask" "F.Paste")
			(net "M2_GPS2_TP2")
			(solder_mask_margin 0)
			(solder_paste_margin 0)
		)
		(pad "49" smd rect
			(at 2.75 -3.9 180)
			(size 0.3 1.55)
			(layers "F.Cu" "F.Mask" "F.Paste")
			(solder_mask_margin 0)
			(solder_paste_margin 0)
		)
		(pad "50" smd rect
			(at 3 3.65 180)
			(size 0.3 1.55)
			(layers "F.Cu" "F.Mask" "F.Paste")
			(net "GPS2_RST")
			(solder_mask_margin 0)
			(solder_paste_margin 0)
		)
		(pad "51" smd rect
			(at 3.25 -3.9 180)
			(size 0.3 1.55)
			(layers "F.Cu" "F.Mask" "F.Paste")
			(net "GND")
			(solder_mask_margin 0)
			(solder_paste_margin 0)
		)
		(pad "52" smd rect
			(at 3.5 3.65 180)
			(size 0.3 1.55)
			(layers "F.Cu" "F.Mask" "F.Paste")
			(solder_mask_margin 0)
			(solder_paste_margin 0)
		)
		(pad "53" smd rect
			(at 3.75 -3.9 180)
			(size 0.3 1.55)
			(layers "F.Cu" "F.Mask" "F.Paste")
			(solder_mask_margin 0)
			(solder_paste_margin 0)
		)
		(pad "54" smd rect
			(at 4 3.65 180)
			(size 0.3 1.55)
			(layers "F.Cu" "F.Mask" "F.Paste")
			(solder_mask_margin 0)
			(solder_paste_margin 0)
		)
		(pad "55" smd rect
			(at 4.25 -3.9 180)
			(size 0.3 1.55)
			(layers "F.Cu" "F.Mask" "F.Paste")
			(solder_mask_margin 0)
			(solder_paste_margin 0)
		)
		(pad "56" smd rect
			(at 4.5 3.65 180)
			(size 0.3 1.55)
			(layers "F.Cu" "F.Mask" "F.Paste")
			(solder_mask_margin 0)
			(solder_paste_margin 0)
		)
		(pad "57" smd rect
			(at 4.75 -3.9 180)
			(size 0.3 1.55)
			(layers "F.Cu" "F.Mask" "F.Paste")
			(net "GND")
			(solder_mask_margin 0)
			(solder_paste_margin 0)
		)
		(pad "58" smd rect
			(at 5 3.65 180)
			(size 0.3 1.55)
			(layers "F.Cu" "F.Mask" "F.Paste")
			(solder_mask_margin 0)
			(solder_paste_margin 0)
		)
		(pad "59" smd rect
			(at 5.25 -3.9 180)
			(size 0.3 1.55)
			(layers "F.Cu" "F.Mask" "F.Paste")
			(solder_mask_margin 0)
			(solder_paste_margin 0)
		)
		(pad "60" smd rect
			(at 5.5 3.65 180)
			(size 0.3 1.55)
			(layers "F.Cu" "F.Mask" "F.Paste")
			(solder_mask_margin 0)
			(solder_paste_margin 0)
		)
		(pad "61" smd rect
			(at 5.75 -3.9 180)
			(size 0.3 1.55)
			(layers "F.Cu" "F.Mask" "F.Paste")
			(solder_mask_margin 0)
			(solder_paste_margin 0)
		)
		(pad "62" smd rect
			(at 6 3.65 180)
			(size 0.3 1.55)
			(layers "F.Cu" "F.Mask" "F.Paste")
			(net "M2_GPS2_RX")
			(solder_mask_margin 0)
			(solder_paste_margin 0)
		)
		(pad "63" smd rect
			(at 6.25 -3.9 180)
			(size 0.3 1.55)
			(layers "F.Cu" "F.Mask" "F.Paste")
			(solder_mask_margin 0)
			(solder_paste_margin 0)
		)
		(pad "64" smd rect
			(at 6.5 3.65 180)
			(size 0.3 1.55)
			(layers "F.Cu" "F.Mask" "F.Paste")
			(net "M2_GPS2_TX")
			(solder_mask_margin 0)
			(solder_paste_margin 0)
		)
		(pad "65" smd rect
			(at 6.75 -3.9 180)
			(size 0.3 1.55)
			(layers "F.Cu" "F.Mask" "F.Paste")
			(solder_mask_margin 0)
			(solder_paste_margin 0)
		)
		(pad "66" smd rect
			(at 7 3.65 180)
			(size 0.3 1.55)
			(layers "F.Cu" "F.Mask" "F.Paste")
			(solder_mask_margin 0)
			(solder_paste_margin 0)
		)
		(pad "67" smd rect
			(at 7.25 -3.9 180)
			(size 0.3 1.55)
			(layers "F.Cu" "F.Mask" "F.Paste")
			(net "GPS2_RST")
			(solder_mask_margin 0)
			(solder_paste_margin 0)
		)
		(pad "68" smd rect
			(at 7.5 3.65 180)
			(size 0.3 1.55)
			(layers "F.Cu" "F.Mask" "F.Paste")
			(solder_mask_margin 0)
			(solder_paste_margin 0)
		)
		(pad "69" smd rect
			(at 7.75 -3.9 180)
			(size 0.3 1.55)
			(layers "F.Cu" "F.Mask" "F.Paste")
			(solder_mask_margin 0)
			(solder_paste_margin 0)
		)
		(pad "70" smd rect
			(at 8 3.65 180)
			(size 0.3 1.55)
			(layers "F.Cu" "F.Mask" "F.Paste")
			(net "GNSS2_P3V3")
			(solder_mask_margin 0)
			(solder_paste_margin 0)
		)
		(pad "71" smd rect
			(at 8.25 -3.9 180)
			(size 0.3 1.55)
			(layers "F.Cu" "F.Mask" "F.Paste")
			(net "GND")
			(solder_mask_margin 0)
			(solder_paste_margin 0)
		)
		(pad "72" smd rect
			(at 8.5 3.65 180)
			(size 0.3 1.55)
			(layers "F.Cu" "F.Mask" "F.Paste")
			(net "GNSS2_P3V3")
			(solder_mask_margin 0)
			(solder_paste_margin 0)
		)
		(pad "73" smd rect
			(at 8.75 -3.9 180)
			(size 0.3 1.55)
			(layers "F.Cu" "F.Mask" "F.Paste")
			(net "GND")
			(solder_mask_margin 0)
			(solder_paste_margin 0)
		)
		(pad "74" smd rect
			(at 9 3.65 180)
			(size 0.3 1.55)
			(layers "F.Cu" "F.Mask" "F.Paste")
			(net "GNSS2_P3V3")
			(solder_mask_margin 0)
			(solder_paste_margin 0)
		)
		(pad "75" smd rect
			(at 9.25 -3.9 180)
			(size 0.3 1.55)
			(layers "F.Cu" "F.Mask" "F.Paste")
			(solder_mask_margin 0)
			(solder_paste_margin 0)
		)
		(pad "76" smd rect
			(at -10.35 -3.125 180)
			(size 1.2 2.75)
			(layers "F.Cu" "F.Mask" "F.Paste")
			(net "GND")
			(solder_mask_margin 0)
			(solder_paste_margin 0)
		)
		(pad "77" smd rect
			(at 10.35 -3.125 180)
			(size 1.2 2.75)
			(layers "F.Cu" "F.Mask" "F.Paste")
			(net "GND")
			(solder_mask_margin 0)
			(solder_paste_margin 0)
		)
	)
)
